# TIMECARD (Time Appliance Project (Time Card)) — schematic netlist excerpt (pin names and nets, part order shuffled) for the footprints in the layout excerpt that follows; sources: Cadence DE-HDL packaged netlist, KiCad conversion of R4006-B0001-02_R01.brd

R125  RESISTOR  100OHM 1%  pkg SMC_0402R_H016  page 26 : \1\ = FPGA_OUT_SMA1_LED_GREEN_N ; \2\ = UNNAMED_14_LED4PV14_I265_4
TP26  TP_PIONT  pkg TP010CT020B030_PTH  page 25 : \1\ = R_SHT3X_RST_N
ME7  MEC_NPTH  pkg MTH100C240N  page 34

(kicad_pcb
	(version 20260206)
	(generator "pcbnew")
	(generator_version "10.0")
	(general
		(thickness 1.6)
		(legacy_teardrops no)
	)
	(paper "A4")
	(title_block
		(title "timecard-production-celestica-r4006 — R4006-B0001-02_R01.brd")
		(comment 1 "Time Appliance Project (Time Card) / footprints 213-215 of 1113")
	)
	(layers
		(0 "F.Cu" signal "TOP")
		(4 "In1.Cu" signal "L02_GND1")
		(6 "In2.Cu" signal "L03_SIG1")
		(8 "In3.Cu" signal "L04_GND2")
		(10 "In4.Cu" signal "L05_VCC1")
		(12 "In5.Cu" signal "L06_VCC2")
		(14 "In6.Cu" signal "L07_GND3")
		(16 "In7.Cu" signal "L08_SIG2")
		(18 "In8.Cu" signal "L09_GND4")
		(2 "B.Cu" signal "BOTTOM")
		(9 "F.Adhes" user "F.Adhesive")
		(11 "B.Adhes" user "B.Adhesive")
		(13 "F.Paste" user "Package Geometry/Pastemask Top")
		(15 "B.Paste" user "Package Geometry/Pastemask Bottom")
		(5 "F.SilkS" user "Ref Des/Silkscreen Top")
		(7 "B.SilkS" user "Ref Des/Silkscreen Bottom")
		(1 "F.Mask" user "Board Geometry/Soldermask Top")
		(3 "B.Mask" user "Board Geometry/Soldermask Bottom")
		(17 "Dwgs.User" user "User.Drawings")
		(19 "Cmts.User" user "User.Comments")
		(21 "Eco1.User" user "User.Eco1")
		(23 "Eco2.User" user "User.Eco2")
		(25 "Edge.Cuts" user "Board Geometry/Outline")
		(27 "Margin" user)
		(31 "F.CrtYd" user "Package Geometry/Place Bound Top")
		(29 "B.CrtYd" user "Package Geometry/Place Bound Bottom")
		(35 "F.Fab" user "Ref Des/Assembly Top")
		(33 "B.Fab" user "Ref Des/Assembly Bottom")
	)
	(footprint ""
		(layer "F.Cu")
		(at 36.466018 -26.934922)
		(property "Reference" "ME7"
			(at -0.398018 -4.420108 0)
			(unlocked yes)
			(layer "F.SilkS")
			(effects
				(font
					(size 0.7874 0.5842)
					(thickness 0.1524)
				)
			)
		)
		(property "Value" ""
			(at 0 0 0)
			(layer "F.Fab")
			(effects
				(font
					(size 1.27 1.27)
				)
			)
		)
		(duplicate_pad_numbers_are_jumpers no)
		(fp_poly
			(pts
				(arc
					(start 3.556 0)
					(mid -3.556 0)
					(end 3.556 0)
				)
			)
			(stroke
				(width 0)
				(type default)
			)
			(fill no)
			(layer "B.CrtYd")
		)
		(fp_poly
			(pts
				(arc
					(start 3.556 0)
					(mid -3.556 0)
					(end 3.556 0)
				)
			)
			(stroke
				(width 0)
				(type default)
			)
			(fill no)
			(layer "F.CrtYd")
		)
		(fp_circle
			(center 0 0)
			(end 3.048 0)
			(stroke
				(width 0.1)
				(type default)
			)
			(fill no)
			(layer "B.Fab")
		)
		(fp_circle
			(center 0 0)
			(end 3.048 0)
			(stroke
				(width 0.1)
				(type default)
			)
			(fill no)
			(layer "F.Fab")
		)
		(pad "" np_thru_hole circle
			(at 0 0)
			(size 2.286 2.286)
			(drill 2.54)
			(layers "*.Cu" "*.Mask")
			(padstack
				(mode front_inner_back)
				(layer "Inner"
					(shape circle)
					(size 2.286 2.286)
					(clearance 0.4445)
				)
				(layer "B.Cu"
					(shape circle)
					(size 2.286 2.286)
				)
			)
		)
		(zone
			(layers "F.Cu" "B.Cu" "In1.Cu" "In2.Cu" "In3.Cu" "In4.Cu" "In5.Cu" "In6.Cu"
				"In7.Cu" "In8.Cu"
			)
			(hatch none 0.5)
			(connect_pads
				(clearance 0)
			)
			(min_thickness 0.25)
			(keepout
				(tracks not_allowed)
				(vias allowed)
				(pads allowed)
				(copperpour not_allowed)
				(footprints allowed)
			)
			(placement
				(enabled no)
				(sheetname "")
			)
			(fill
				(thermal_gap 0.5)
				(thermal_bridge_width 0.5)
				(island_removal_mode 0)
			)
			(polygon
				(pts
					(arc
						(start 38.040818 -26.934922)
						(mid 34.891218 -26.934922)
						(end 38.040818 -26.934922)
					)
				)
			)
		)
	)
	(footprint ""
		(layer "F.Cu")
		(at 9.4234 -39.318692 90)
		(property "Reference" "R125"
			(at 2.337308 -0.17145 90)
			(unlocked yes)
			(layer "F.SilkS")
			(effects
				(font
					(size 0.635 0.4064)
					(thickness 0.1524)
				)
			)
		)
		(property "Value" "VAL*"
			(at 0.02032 2.13233 90)
			(unlocked yes)
			(layer "F.Fab")
			(hide yes)
			(effects
				(font
					(size 0.7874 0.5842)
					(thickness 0.1524)
				)
			)
		)
		(property "Device Type" "RESISTOR-G155-11000-01,100OHM,A"
			(at 0.008382 1.210564 90)
			(unlocked yes)
			(layer "F.Fab")
			(hide yes)
			(effects
				(font
					(size 0.7874 0.5842)
					(thickness 0.1524)
				)
			)
		)
		(property "User Part Number" "PARTNUM*"
			(at 0.02032 4.024884 90)
			(unlocked yes)
			(layer "Cmts.User")
			(hide yes)
			(effects
				(font
					(size 0.7874 0.5842)
					(thickness 0.1524)
				)
			)
		)
		(property "Tolerance" "TOL*"
			(at 0.044704 3.05435 90)
			(unlocked yes)
			(layer "Cmts.User")
			(hide yes)
			(effects
				(font
					(size 0.7874 0.5842)
					(thickness 0.1524)
				)
			)
		)
		(duplicate_pad_numbers_are_jumpers no)
		(fp_line
			(start 1.143 -0.5588)
			(end -1.143 -0.5588)
			(stroke
				(width 0.1)
				(type default)
			)
			(layer "F.SilkS")
		)
		(fp_line
			(start -1.143 -0.5588)
			(end -1.143 0.5588)
			(stroke
				(width 0.1)
				(type default)
			)
			(layer "F.SilkS")
		)
		(fp_line
			(start 1.143 0.5588)
			(end 1.143 -0.5588)
			(stroke
				(width 0.1)
				(type default)
			)
			(layer "F.SilkS")
		)
		(fp_line
			(start -1.143 0.5588)
			(end 1.143 0.5588)
			(stroke
				(width 0.1)
				(type default)
			)
			(layer "F.SilkS")
		)
		(fp_poly
			(pts
				(xy -1.143 0.5588) (xy 1.143 0.5588) (xy 1.143 -0.5588) (xy -1.143 -0.5588)
			)
			(stroke
				(width 0)
				(type default)
			)
			(fill no)
			(layer "F.CrtYd")
		)
		(fp_line
			(start 0.508 -0.3048)
			(end -0.508 -0.3048)
			(stroke
				(width 0.1)
				(type default)
			)
			(layer "F.Fab")
		)
		(fp_line
			(start -0.508 -0.3048)
			(end -0.508 0.3048)
			(stroke
				(width 0.1)
				(type default)
			)
			(layer "F.Fab")
		)
		(fp_line
			(start 0.508 0.3048)
			(end 0.508 -0.3048)
			(stroke
				(width 0.1)
				(type default)
			)
			(layer "F.Fab")
		)
		(fp_line
			(start -0.508 0.3048)
			(end 0.508 0.3048)
			(stroke
				(width 0.1)
				(type default)
			)
			(layer "F.Fab")
		)
		(pad "1" smd rect
			(at -0.5334 0 90)
			(size 0.7112 0.6096)
			(layers "F.Cu" "F.Mask" "F.Paste")
			(net "FPGA_OUT_SMA1_LED_GREEN_N")
		)
		(pad "2" smd rect
			(at 0.5334 0 90)
			(size 0.7112 0.6096)
			(layers "F.Cu" "F.Mask" "F.Paste")
			(net "UNNAMED_14_LED4PV14_I265_4")
		)
		(zone
			(layer "F.Cu")
			(hatch none 0.5)
			(connect_pads
				(clearance 0)
			)
			(min_thickness 0.25)
			(keepout
				(tracks not_allowed)
				(vias allowed)
				(pads allowed)
				(copperpour not_allowed)
				(footprints allowed)
			)
			(placement
				(enabled no)
				(sheetname "")
			)
			(fill
				(thermal_gap 0.5)
				(thermal_bridge_width 0.5)
				(island_removal_mode 0)
			)
			(polygon
				(pts
					(xy 9.7282 -39.242492) (xy 9.7282 -39.394892) (xy 9.1186 -39.394892) (xy 9.1186 -39.242492)
				)
			)
		)
		(zone
			(layer "F.Cu")
			(hatch none 0.5)
			(connect_pads
				(clearance 0)
			)
			(min_thickness 0.25)
			(keepout
				(tracks allowed)
				(vias not_allowed)
				(pads allowed)
				(copperpour not_allowed)
				(footprints allowed)
			)
			(placement
				(enabled no)
				(sheetname "")
			)
			(fill
				(thermal_gap 0.5)
				(thermal_bridge_width 0.5)
				(island_removal_mode 0)
			)
			(polygon
				(pts
					(xy 9.7282 -39.242492) (xy 9.7282 -39.394892) (xy 9.1186 -39.394892) (xy 9.1186 -39.242492)
				)
			)
		)
	)
	(footprint ""
		(layer "F.Cu")
		(at 151.257 -60.706)
		(property "Reference" "TP26"
			(at -0.7112 -1.48463 0)
			(unlocked yes)
			(layer "F.SilkS")
			(effects
				(font
					(size 0.7874 0.5842)
					(thickness 0.1524)
				)
				(justify left)
			)
		)
		(property "Value" ""
			(at 0 0 0)
			(layer "F.Fab")
			(effects
				(font
					(size 1.27 1.27)
				)
			)
		)
		(property "Device Type" "TP_PIONT-TP010CT020B030_PTH-TPA"
			(at -1.341882 0.996696 0)
			(unlocked yes)
			(layer "F.Fab")
			(hide yes)
			(effects
				(font
					(size 0.7874 0.5842)
					(thickness 0.000001)
				)
				(justify left)
			)
		)
		(duplicate_pad_numbers_are_jumpers no)
		(fp_poly
			(pts
				(arc
					(start 0.889 0)
					(mid -0.889 0)
					(end 0.889 0)
				)
			)
			(stroke
				(width 0)
				(type default)
			)
			(fill no)
			(layer "B.CrtYd")
		)
		(fp_poly
			(pts
				(arc
					(start 0.889 0)
					(mid -0.889 0)
					(end 0.889 0)
				)
			)
			(stroke
				(width 0)
				(type default)
			)
			(fill no)
			(layer "F.CrtYd")
		)
		(pad "1" thru_hole circle
			(at 0 0)
			(size 0.508 0.508)
			(drill 0.254)
			(layers "*.Cu" "*.Mask")
			(remove_unused_layers no)
			(net "R_SHT3X_RST_N")
			(clearance 0.1016)
			(padstack
				(mode front_inner_back)
				(layer "Inner"
					(shape circle)
					(size 0.508 0.508)
					(clearance 0.1016)
				)
				(layer "B.Cu"
					(shape circle)
					(size 0.762 0.762)
					(clearance -0.0254)
				)
			)
		)
	)
)
